# T6G (Grand Teton) — schematic netlist excerpt (pin names and nets, part order shuffled) for the footprints in the layout excerpt that follows; sources: Cadence DE-HDL packaged netlist, KiCad conversion of 04192023_DAF0TMB3IC0_F0TG_MB_C_brd_V02_OCP.brd

C1994  Q_CAP_DIFFBUS  DIFF BUS_0.22UF 6.3V 20% X6S  pkg C0201  page 67 : \1\ = P3E_CPU0_P4_TX_C_DN<1> ; \2\ = P3E_CPU0_P4_TX_DN<1>
PR3786  Q_RES  160K 1% CHIP  pkg 0402LF  page 134 : A = P12V_AUX ; B = P12V_OCP_UV_1

(kicad_pcb
	(version 20260206)
	(generator "pcbnew")
	(generator_version "10.0")
	(general
		(thickness 1.6)
		(legacy_teardrops no)
	)
	(paper "A4")
	(title_block
		(title "04192023_DAF0TMB3IC0_F0TG_MB_C_brd_V02_OCP.brd")
		(comment 1 "Grand Teton / footprints 4859-4860 of 8354")
	)
	(layers
		(0 "F.Cu" signal "TOP")
		(4 "In1.Cu" signal "GND")
		(6 "In2.Cu" signal "IN1")
		(8 "In3.Cu" signal "GND1")
		(10 "In4.Cu" signal "IN2")
		(12 "In5.Cu" signal "GND2")
		(14 "In6.Cu" signal "IN3")
		(16 "In7.Cu" signal "GND3")
		(18 "In8.Cu" signal "VCC")
		(20 "In9.Cu" signal "VCC1")
		(22 "In10.Cu" signal "GND4")
		(24 "In11.Cu" signal "IN4")
		(26 "In12.Cu" signal "GND5")
		(28 "In13.Cu" signal "IN5")
		(30 "In14.Cu" signal "GND6")
		(32 "In15.Cu" signal "IN6")
		(34 "In16.Cu" signal "GND7")
		(2 "B.Cu" signal "BOTTOM")
		(9 "F.Adhes" user "F.Adhesive")
		(11 "B.Adhes" user "B.Adhesive")
		(13 "F.Paste" user "Package Geometry/Pastemask Top")
		(15 "B.Paste" user "Package Geometry/Pastemask Bottom")
		(5 "F.SilkS" user "Ref Des/Silkscreen Top")
		(7 "B.SilkS" user "Ref Des/Silkscreen Bottom")
		(1 "F.Mask" user "Board Geometry/Soldermask Top")
		(3 "B.Mask" user "Board Geometry/Soldermask Bottom")
		(17 "Dwgs.User" user "User.Drawings")
		(19 "Cmts.User" user "User.Comments")
		(21 "Eco1.User" user "User.Eco1")
		(23 "Eco2.User" user "User.Eco2")
		(25 "Edge.Cuts" user "Board Geometry/Outline")
		(27 "Margin" user)
		(31 "F.CrtYd" user "Package Geometry/Place Bound Top")
		(29 "B.CrtYd" user "Package Geometry/Place Bound Bottom")
		(35 "F.Fab" user "Ref Des/Assembly Top")
		(33 "B.Fab" user "Ref Des/Assembly Bottom")
	)
	(footprint ""
		(layer "F.Cu")
		(at 447.557652 -18.449798)
		(property "Reference" "PR3786"
			(at 0 0 0)
			(layer "F.SilkS")
			(hide yes)
			(effects
				(font
					(size 1.27 1.27)
				)
			)
		)
		(property "Value" ""
			(at 0 0 0)
			(layer "F.Fab")
			(effects
				(font
					(size 1.27 1.27)
				)
			)
		)
		(duplicate_pad_numbers_are_jumpers no)
		(fp_line
			(start -0.7874 -0.4064)
			(end 0.7874 -0.4064)
			(stroke
				(width 0.1524)
				(type default)
			)
			(layer "F.SilkS")
		)
		(fp_line
			(start -0.7874 0.4064)
			(end -0.7874 -0.4064)
			(stroke
				(width 0.1524)
				(type default)
			)
			(layer "F.SilkS")
		)
		(fp_line
			(start 0.7874 -0.4064)
			(end 0.7874 0.4064)
			(stroke
				(width 0.1524)
				(type default)
			)
			(layer "F.SilkS")
		)
		(fp_line
			(start 0.7874 0.4064)
			(end -0.7874 0.4064)
			(stroke
				(width 0.1524)
				(type default)
			)
			(layer "F.SilkS")
		)
		(fp_line
			(start -0.67945 -0.305054)
			(end -0.12065 -0.305054)
			(stroke
				(width 0.1)
				(type default)
			)
			(layer "F.Fab")
		)
		(fp_line
			(start -0.67945 0.3048)
			(end -0.67945 -0.305054)
			(stroke
				(width 0.1)
				(type default)
			)
			(layer "F.Fab")
		)
		(fp_line
			(start -0.12065 -0.305054)
			(end -0.12065 -0.2794)
			(stroke
				(width 0.1)
				(type default)
			)
			(layer "F.Fab")
		)
		(fp_line
			(start -0.12065 -0.2794)
			(end 0.12065 -0.2794)
			(stroke
				(width 0.1)
				(type default)
			)
			(layer "F.Fab")
		)
		(fp_line
			(start -0.12065 0.2794)
			(end -0.12065 0.3048)
			(stroke
				(width 0.1)
				(type default)
			)
			(layer "F.Fab")
		)
		(fp_line
			(start -0.12065 0.3048)
			(end -0.67945 0.3048)
			(stroke
				(width 0.1)
				(type default)
			)
			(layer "F.Fab")
		)
		(fp_line
			(start 0.120396 0.2794)
			(end -0.12065 0.2794)
			(stroke
				(width 0.1)
				(type default)
			)
			(layer "F.Fab")
		)
		(fp_line
			(start 0.120396 0.3048)
			(end 0.120396 0.2794)
			(stroke
				(width 0.1)
				(type default)
			)
			(layer "F.Fab")
		)
		(fp_line
			(start 0.12065 -0.3048)
			(end 0.67945 -0.3048)
			(stroke
				(width 0.1)
				(type default)
			)
			(layer "F.Fab")
		)
		(fp_line
			(start 0.12065 -0.2794)
			(end 0.12065 -0.3048)
			(stroke
				(width 0.1)
				(type default)
			)
			(layer "F.Fab")
		)
		(fp_line
			(start 0.67945 -0.3048)
			(end 0.67945 0.3048)
			(stroke
				(width 0.1)
				(type default)
			)
			(layer "F.Fab")
		)
		(fp_line
			(start 0.67945 0.3048)
			(end 0.120396 0.3048)
			(stroke
				(width 0.1)
				(type default)
			)
			(layer "F.Fab")
		)
		(pad "1" smd circle
			(at -0.40005 0)
			(size 0 0)
			(layers "F.Cu" "F.Mask" "F.Paste")
			(net "P12V_AUX")
		)
		(pad "2" smd circle
			(at 0.40005 0)
			(size 0 0)
			(layers "F.Cu" "F.Mask" "F.Paste")
			(net "P12V_OCP_UV_1")
		)
	)
	(footprint ""
		(layer "F.Cu")
		(at 239.152684 -54.736238)
		(property "Reference" "C1994"
			(at 0 0 0)
			(layer "F.SilkS")
			(hide yes)
			(effects
				(font
					(size 1.27 1.27)
				)
			)
		)
		(property "Value" ""
			(at 0 0 0)
			(layer "F.Fab")
			(effects
				(font
					(size 1.27 1.27)
				)
			)
		)
		(duplicate_pad_numbers_are_jumpers no)
		(fp_line
			(start -0.299974 -0.150114)
			(end 0.299974 -0.150114)
			(stroke
				(width 0.1)
				(type default)
			)
			(layer "F.Fab")
		)
		(fp_line
			(start -0.299974 0.150114)
			(end -0.299974 -0.150114)
			(stroke
				(width 0.1)
				(type default)
			)
			(layer "F.Fab")
		)
		(fp_line
			(start 0.299974 -0.150114)
			(end 0.299974 0.150114)
			(stroke
				(width 0.1)
				(type default)
			)
			(layer "F.Fab")
		)
		(fp_line
			(start 0.299974 0.150114)
			(end -0.299974 0.150114)
			(stroke
				(width 0.1)
				(type default)
			)
			(layer "F.Fab")
		)
		(pad "1" smd rect
			(at -0.2667 0)
			(size 0.3048 0.381)
			(layers "F.Cu" "F.Mask" "F.Paste")
			(net "P3E_CPU0_P4_TX_C_DN<1>")
		)
		(pad "2" smd rect
			(at 0.2667 0)
			(size 0.3048 0.381)
			(layers "F.Cu" "F.Mask" "F.Paste")
			(net "P3E_CPU0_P4_TX_DN<1>")
		)
	)
)
